(kicad_pcb
	(version 20221018)
	(generator pcbnew)
	(general
    (thickness 1.518)
  )
	(paper "A4")
	(title_block
    (title "Kria K26 Devboard")
    (date "2024-03-26")
    (rev "1.2.5")
    (comment 1 "www.antmicro.com")
    (comment 2 "Antmicro Ltd.")
		(comment 9 "footprints 657-660 of 660")
	)
	(layers
    (0 "F.Cu" mixed)
    (1 "In1.Cu" power)
    (2 "In2.Cu" mixed)
    (3 "In3.Cu" power)
    (4 "In4.Cu" mixed)
    (5 "In5.Cu" power)
    (6 "In6.Cu" mixed)
    (31 "B.Cu" power)
    (32 "B.Adhes" user "B.Adhesive")
    (33 "F.Adhes" user "F.Adhesive")
    (34 "B.Paste" user)
    (35 "F.Paste" user)
    (36 "B.SilkS" user "B.Silkscreen")
    (37 "F.SilkS" user "F.Silkscreen")
    (38 "B.Mask" user)
    (39 "F.Mask" user)
    (40 "Dwgs.User" user "User.Drawings")
    (41 "Cmts.User" user "User.Comments")
    (42 "Eco1.User" user "User.Eco1")
    (43 "Eco2.User" user "User.Eco2")
    (44 "Edge.Cuts" user)
    (45 "Margin" user)
    (46 "B.CrtYd" user "B.Courtyard")
    (47 "F.CrtYd" user "F.Courtyard")
    (48 "B.Fab" user)
    (49 "F.Fab" user)
  )
	(footprint "kria-k26-devboard-footprints:R_0402_1005Metric" (layer "B.Cu")
    (at 97.8 91)
    (descr "Resistor SMD 0402")
    (tags "resistor SMD 0402")
    (property "Author" "Antmicro")
    (property "Current" "1A")
    (property "DNP" "DNP")
    (property "License" "Apache-2.0")
    (property "MPN" "ERJ2GE0R00X")
    (property "Manufacturer" "Panasonic")
    (property "Sheetfile" "k26_som.kicad_sch")
    (property "Sheetname" "Xilinx K26 SOM")
    (property "Tolerance" "")
    (property "Val" "0R")
    (property "dnp" "")
    (property "exclude_from_bom" "")
    (property "ki_description" "0R resistor in 0402 package with unspecified tolerance")
    (attr exclude_from_pos_files exclude_from_bom)
    (fp_text reference "R178" (at 1.42 1.33 180) (layer "B.SilkS")
        (effects (font (size 0.7 0.7) (thickness 0.15)) (justify left bottom mirror))
    )
    (fp_text value "R_0R_0402" (at 0 -1.4 180) (layer "B.Fab") hide
        (effects (font (size 0.7 0.7) (thickness 0.15)) (justify left bottom mirror))
    )
    (fp_text user "License: Apache-2.0" (at -0.95 -5.169 180) (layer "B.Fab") hide
        (effects (font (size 0.7 0.7) (thickness 0.15)) (justify left bottom mirror))
    )
    (fp_text user "${REFERENCE}" (at -0.95 -3.168 180) (layer "B.Fab") hide
        (effects (font (size 0.7 0.7) (thickness 0.15)) (justify left bottom mirror))
    )
    (fp_text user "Author: Antmicro" (at -0.95 -4.169 180) (layer "B.Fab") hide
        (effects (font (size 0.7 0.7) (thickness 0.15)) (justify left bottom mirror))
    )
    (fp_rect (start -0.93 0.47) (end 0.93 -0.47)
      (stroke (width 0.05) (type solid)) (fill none) (layer "B.CrtYd"))
    (fp_rect (start -0.5 0.25) (end 0.5 -0.25)
      (stroke (width 0.15) (type solid)) (fill none) (layer "B.Fab"))
    (pad "1" smd roundrect (at -0.485 0) (size 0.59 0.64) (layers "B.Cu" "B.Paste" "B.Mask") (roundrect_rratio 0.25)
      (net 6 "/Xilinx K26 SOM/HDA20") (pintype "passive"))
    (pad "2" smd roundrect (at 0.485 0) (size 0.59 0.64) (layers "B.Cu" "B.Paste" "B.Mask") (roundrect_rratio 0.25)
      (net 431 "Net-(Q19-C)") (pintype "passive"))
  )
	(footprint "kria-k26-devboard-footprints:Fiducial_1mm_Mask2mm" (layer "B.Cu")
    (at 82 150.4 -90)
    (descr "Circular Fiducial, 1mm bare copper, 3mm soldermask opening")
    (tags "fiducial")
    (attr smd board_only exclude_from_bom)
    (fp_text reference "FID4" (at -0.07 -3.21) (layer "B.SilkS")
        (effects (font (size 1 1) (thickness 0.15)) (justify mirror))
    )
    (fp_text value "Fiducial_1mm_Mask2mm" (at 0 -2.6035 90) (layer "B.Fab") hide
        (effects (font (size 1 1) (thickness 0.15)) (justify mirror))
    )
    (fp_text user "${REFERENCE}" (at 0 0 90) (layer "B.Fab")
        (effects (font (size 0.4 0.4) (thickness 0.06)) (justify mirror))
    )
    (fp_text user "Author: Antmicro" (at -1.25 -5.803 90) (layer "B.Fab") hide
        (effects (font (size 0.7 0.7) (thickness 0.15)) (justify left bottom mirror))
    )
    (fp_text user "License: Apache-2.0" (at -1.25 -7.003 90) (layer "B.Fab") hide
        (effects (font (size 0.7 0.7) (thickness 0.15)) (justify left bottom mirror))
    )
    (fp_circle (center 0 0) (end 1.24 0)
      (stroke (width 0.05) (type solid)) (fill none) (layer "B.CrtYd"))
    (fp_circle (center 0 0) (end 0.999 0)
      (stroke (width 0.15) (type solid)) (fill none) (layer "B.Fab"))
    (pad "" smd circle (at 0 0 270) (size 1 1) (layers "B.Cu" "B.Mask")
      (solder_mask_margin 0.5) (clearance 0.5))
  )
	(footprint "kria-k26-devboard-footprints:C_0402_1005Metric" (layer "B.Cu")
    (at 108.95 86.55)
    (descr "Capacitor SMD 0402")
    (tags "capacitor SMD 0402")
    (property "Author" "Antmicro")
    (property "Dielectric" "X5R")
    (property "License" "Apache-2.0")
    (property "MPN" "GRM155R61H104KE14D")
    (property "Manufacturer" "Murata")
    (property "Sheetfile" "k26_som.kicad_sch")
    (property "Sheetname" "Xilinx K26 SOM")
    (property "Val" "100n")
    (property "Voltage" "50V")
    (property "ki_description" " ")
    (attr smd)
    (fp_text reference "C251" (at 3.68 1.56 180) (layer "B.SilkS")
        (effects (font (size 0.7 0.7) (thickness 0.15)) (justify left bottom mirror))
    )
    (fp_text value "C_100n_0402" (at 0 -1.4 180) (layer "B.Fab") hide
        (effects (font (size 0.7 0.7) (thickness 0.15)) (justify left bottom mirror))
    )
    (fp_text user "${REFERENCE}" (at -0.932 -3.168 180) (layer "B.Fab") hide
        (effects (font (size 0.7 0.7) (thickness 0.15)) (justify left bottom mirror))
    )
    (fp_text user "License: Apache-2.0" (at -0.932 -5.17 180) (layer "B.Fab") hide
        (effects (font (size 0.7 0.7) (thickness 0.15)) (justify left bottom mirror))
    )
    (fp_text user "Author: Antmicro" (at -0.932 -4.17 180) (layer "B.Fab") hide
        (effects (font (size 0.7 0.7) (thickness 0.15)) (justify left bottom mirror))
    )
    (fp_rect (start -0.94 0.47) (end 0.94 -0.47)
      (stroke (width 0.05) (type solid)) (fill none) (layer "B.CrtYd"))
    (fp_rect (start -0.499 0.249) (end 0.499 -0.249)
      (stroke (width 0.15) (type solid)) (fill none) (layer "B.Fab"))
    (pad "1" smd roundrect (at -0.484 0) (size 0.59 0.64) (layers "B.Cu" "B.Paste" "B.Mask") (roundrect_rratio 0.25)
      (net 243 "Net-(Q6-D)") (pintype "passive"))
    (pad "2" smd roundrect (at 0.484 0) (size 0.59 0.64) (layers "B.Cu" "B.Paste" "B.Mask") (roundrect_rratio 0.25)
      (net 1 "GND") (pintype "passive"))
  )
	(footprint "kria-k26-devboard-footprints:R_0402_1005Metric" (layer "B.Cu")
    (at 145.566648 76.145761 90)
    (descr "Resistor SMD 0402")
    (tags "resistor SMD 0402")
    (property "Author" "Antmicro")
    (property "License" "Apache-2.0")
    (property "MPN" "CR0402-FX-1473GLF")
    (property "Manufacturer" "Bourns")
    (property "Sheetfile" "dc-dc-conventers.kicad_sch")
    (property "Sheetname" "DC/DC conventers")
    (property "Tolerance" "1%")
    (property "Val" "147k")
    (property "ki_description" "147k resistor in 0402 package with 1% tolerance")
    (attr smd)
    (fp_text reference "R122" (at 1.5 -2.44 270) (layer "B.SilkS")
        (effects (font (size 0.7 0.7) (thickness 0.15)) (justify left bottom mirror))
    )
    (fp_text value "R_147k_0402" (at 0 -1.4 270) (layer "B.Fab") hide
        (effects (font (size 0.7 0.7) (thickness 0.15)) (justify left bottom mirror))
    )
    (fp_text user "${REFERENCE}" (at -0.95 -3.168 270) (layer "B.Fab") hide
        (effects (font (size 0.7 0.7) (thickness 0.15)) (justify left bottom mirror))
    )
    (fp_text user "Author: Antmicro" (at -0.95 -4.169 270) (layer "B.Fab") hide
        (effects (font (size 0.7 0.7) (thickness 0.15)) (justify left bottom mirror))
    )
    (fp_text user "License: Apache-2.0" (at -0.95 -5.169 270) (layer "B.Fab") hide
        (effects (font (size 0.7 0.7) (thickness 0.15)) (justify left bottom mirror))
    )
    (fp_rect (start -0.93 0.47) (end 0.93 -0.47)
      (stroke (width 0.05) (type solid)) (fill none) (layer "B.CrtYd"))
    (fp_rect (start -0.5 0.25) (end 0.5 -0.25)
      (stroke (width 0.15) (type solid)) (fill none) (layer "B.Fab"))
    (pad "1" smd roundrect (at -0.485 0 90) (size 0.59 0.64) (layers "B.Cu" "B.Paste" "B.Mask") (roundrect_rratio 0.25)
      (net 772 "/Power Supply/DC/DC conventers/USB_5V_OUT") (pintype "passive"))
    (pad "2" smd roundrect (at 0.485 0 90) (size 0.59 0.64) (layers "B.Cu" "B.Paste" "B.Mask") (roundrect_rratio 0.25)
      (net 254 "Net-(U47-FB)") (pintype "passive"))
  )
)
